(kicad_pcb
	(version 20260206)
	(generator "pcbnew")
	(generator_version "10.0")
	(general
		(thickness 1.6)
		(legacy_teardrops no)
	)
	(paper "A4")
	(title_block
		(title "03242023_DA0F0TMBIJ0_F0T_Motherboard_J_brd_V01_OCP.brd")
		(comment 1 "Grand Teton / footprints 4977-4982 of 6105")
	)
	(layers
		(0 "F.Cu" signal "TOP")
		(4 "In1.Cu" signal "GND")
		(6 "In2.Cu" signal "IN1")
		(8 "In3.Cu" signal "GND1")
		(10 "In4.Cu" signal "IN2")
		(12 "In5.Cu" signal "GND2")
		(14 "In6.Cu" signal "IN3")
		(16 "In7.Cu" signal "GND3")
		(18 "In8.Cu" signal "VCC")
		(20 "In9.Cu" signal "VCC1")
		(22 "In10.Cu" signal "GND4")
		(24 "In11.Cu" signal "IN4")
		(26 "In12.Cu" signal "GND5")
		(28 "In13.Cu" signal "IN5")
		(30 "In14.Cu" signal "GND6")
		(32 "In15.Cu" signal "IN6")
		(34 "In16.Cu" signal "GND7")
		(2 "B.Cu" signal "BOTTOM")
		(9 "F.Adhes" user "F.Adhesive")
		(11 "B.Adhes" user "B.Adhesive")
		(13 "F.Paste" user "Package Geometry/Pastemask Top")
		(15 "B.Paste" user "Package Geometry/Pastemask Bottom")
		(5 "F.SilkS" user "Ref Des/Silkscreen Top")
		(7 "B.SilkS" user "Ref Des/Silkscreen Bottom")
		(1 "F.Mask" user "Board Geometry/Soldermask Top")
		(3 "B.Mask" user "Board Geometry/Soldermask Bottom")
		(17 "Dwgs.User" user "User.Drawings")
		(19 "Cmts.User" user "User.Comments")
		(21 "Eco1.User" user "User.Eco1")
		(23 "Eco2.User" user "User.Eco2")
		(25 "Edge.Cuts" user "Board Geometry/Outline")
		(27 "Margin" user)
		(31 "F.CrtYd" user "Package Geometry/Place Bound Top")
		(29 "B.CrtYd" user "Package Geometry/Place Bound Bottom")
		(35 "F.Fab" user "Ref Des/Assembly Top")
		(33 "B.Fab" user "Ref Des/Assembly Bottom")
	)
	(footprint ""
		(layer "B.Cu")
		(at 34.014156 -395.918436 -90)
		(property "Reference" "C2356"
			(at 0 0 90)
			(layer "B.SilkS")
			(hide yes)
			(effects
				(font
					(size 1.27 1.27)
				)
				(justify mirror)
			)
		)
		(property "Value" ""
			(at 0 0 90)
			(layer "B.Fab")
			(effects
				(font
					(size 1.27 1.27)
				)
				(justify mirror)
			)
		)
		(duplicate_pad_numbers_are_jumpers no)
		(fp_line
			(start -1.524 0.762)
			(end 1.524 0.762)
			(stroke
				(width 0.1524)
				(type default)
			)
			(layer "B.SilkS")
		)
		(fp_line
			(start 1.524 0.762)
			(end 1.524 -0.762)
			(stroke
				(width 0.1524)
				(type default)
			)
			(layer "B.SilkS")
		)
		(fp_line
			(start -1.524 -0.762)
			(end -1.524 0.762)
			(stroke
				(width 0.1524)
				(type default)
			)
			(layer "B.SilkS")
		)
		(fp_line
			(start 1.524 -0.762)
			(end -1.524 -0.762)
			(stroke
				(width 0.1524)
				(type default)
			)
			(layer "B.SilkS")
		)
		(fp_line
			(start -1.1049 0.724916)
			(end -1.1049 -0.724916)
			(stroke
				(width 0.1)
				(type default)
			)
			(layer "B.Fab")
		)
		(fp_line
			(start 1.1049 0.724916)
			(end -1.1049 0.724916)
			(stroke
				(width 0.1)
				(type default)
			)
			(layer "B.Fab")
		)
		(fp_line
			(start -1.1049 -0.724916)
			(end 1.1049 -0.724916)
			(stroke
				(width 0.1)
				(type default)
			)
			(layer "B.Fab")
		)
		(fp_line
			(start 1.1049 -0.724916)
			(end 1.1049 0.724916)
			(stroke
				(width 0.1)
				(type default)
			)
			(layer "B.Fab")
		)
		(pad "1" smd rect
			(at 0.889 0 270)
			(size 1.016 1.27)
			(layers "B.Cu" "B.Mask" "B.Paste")
			(net "P3V3_AUX")
		)
		(pad "2" smd rect
			(at -0.889 0 270)
			(size 1.016 1.27)
			(layers "B.Cu" "B.Mask" "B.Paste")
			(net "GND")
		)
	)
	(footprint ""
		(layer "B.Cu")
		(at 22.989032 -171.165774 180)
		(property "Reference" "R4595"
			(at 0 0 0)
			(layer "B.SilkS")
			(hide yes)
			(effects
				(font
					(size 1.27 1.27)
				)
				(justify mirror)
			)
		)
		(property "Value" ""
			(at 0 0 0)
			(layer "B.Fab")
			(effects
				(font
					(size 1.27 1.27)
				)
				(justify mirror)
			)
		)
		(duplicate_pad_numbers_are_jumpers no)
		(fp_line
			(start 0.7874 0.4064)
			(end 0.7874 -0.4064)
			(stroke
				(width 0.1524)
				(type default)
			)
			(layer "B.SilkS")
		)
		(fp_line
			(start 0.7874 -0.4064)
			(end -0.7874 -0.4064)
			(stroke
				(width 0.1524)
				(type default)
			)
			(layer "B.SilkS")
		)
		(fp_line
			(start -0.7874 0.4064)
			(end 0.7874 0.4064)
			(stroke
				(width 0.1524)
				(type default)
			)
			(layer "B.SilkS")
		)
		(fp_line
			(start -0.7874 -0.4064)
			(end -0.7874 0.4064)
			(stroke
				(width 0.1524)
				(type default)
			)
			(layer "B.SilkS")
		)
		(fp_line
			(start 0.67945 0.3048)
			(end 0.67945 -0.305054)
			(stroke
				(width 0.1)
				(type default)
			)
			(layer "B.Fab")
		)
		(fp_line
			(start 0.67945 -0.305054)
			(end 0.12065 -0.305054)
			(stroke
				(width 0.1)
				(type default)
			)
			(layer "B.Fab")
		)
		(fp_line
			(start 0.12065 0.3048)
			(end 0.67945 0.3048)
			(stroke
				(width 0.1)
				(type default)
			)
			(layer "B.Fab")
		)
		(fp_line
			(start 0.12065 0.2794)
			(end 0.12065 0.3048)
			(stroke
				(width 0.1)
				(type default)
			)
			(layer "B.Fab")
		)
		(fp_line
			(start 0.12065 -0.2794)
			(end -0.12065 -0.2794)
			(stroke
				(width 0.1)
				(type default)
			)
			(layer "B.Fab")
		)
		(fp_line
			(start 0.12065 -0.305054)
			(end 0.12065 -0.2794)
			(stroke
				(width 0.1)
				(type default)
			)
			(layer "B.Fab")
		)
		(fp_line
			(start -0.120396 0.3048)
			(end -0.120396 0.2794)
			(stroke
				(width 0.1)
				(type default)
			)
			(layer "B.Fab")
		)
		(fp_line
			(start -0.120396 0.2794)
			(end 0.12065 0.2794)
			(stroke
				(width 0.1)
				(type default)
			)
			(layer "B.Fab")
		)
		(fp_line
			(start -0.12065 -0.2794)
			(end -0.12065 -0.3048)
			(stroke
				(width 0.1)
				(type default)
			)
			(layer "B.Fab")
		)
		(fp_line
			(start -0.12065 -0.3048)
			(end -0.67945 -0.3048)
			(stroke
				(width 0.1)
				(type default)
			)
			(layer "B.Fab")
		)
		(fp_line
			(start -0.67945 0.3048)
			(end -0.120396 0.3048)
			(stroke
				(width 0.1)
				(type default)
			)
			(layer "B.Fab")
		)
		(fp_line
			(start -0.67945 -0.3048)
			(end -0.67945 0.3048)
			(stroke
				(width 0.1)
				(type default)
			)
			(layer "B.Fab")
		)
		(pad "1" smd circle
			(at 0.40005 0)
			(size 0 0)
			(layers "B.Cu" "B.Mask" "B.Paste")
			(net "SMB_VR_3V3AUX_SCL_R")
		)
		(pad "2" smd circle
			(at -0.40005 0)
			(size 0 0)
			(layers "B.Cu" "B.Mask" "B.Paste")
			(net "SMB_CLK_PVCCD_HV_CPU1")
		)
	)
	(footprint ""
		(layer "B.Cu")
		(at 338.998814 -190.756286 90)
		(property "Reference" "R688"
			(at 0 0 90)
			(layer "B.SilkS")
			(hide yes)
			(effects
				(font
					(size 1.27 1.27)
				)
				(justify mirror)
			)
		)
		(property "Value" ""
			(at 0 0 90)
			(layer "B.Fab")
			(effects
				(font
					(size 1.27 1.27)
				)
				(justify mirror)
			)
		)
		(duplicate_pad_numbers_are_jumpers no)
		(fp_line
			(start 0.7874 -0.4064)
			(end -0.7874 -0.4064)
			(stroke
				(width 0.1524)
				(type default)
			)
			(layer "B.SilkS")
		)
		(fp_line
			(start -0.7874 -0.4064)
			(end -0.7874 0.4064)
			(stroke
				(width 0.1524)
				(type default)
			)
			(layer "B.SilkS")
		)
		(fp_line
			(start 0.7874 0.4064)
			(end 0.7874 -0.4064)
			(stroke
				(width 0.1524)
				(type default)
			)
			(layer "B.SilkS")
		)
		(fp_line
			(start -0.7874 0.4064)
			(end 0.7874 0.4064)
			(stroke
				(width 0.1524)
				(type default)
			)
			(layer "B.SilkS")
		)
		(fp_line
			(start 0.67945 -0.305054)
			(end 0.12065 -0.305054)
			(stroke
				(width 0.1)
				(type default)
			)
			(layer "B.Fab")
		)
		(fp_line
			(start 0.12065 -0.305054)
			(end 0.12065 -0.2794)
			(stroke
				(width 0.1)
				(type default)
			)
			(layer "B.Fab")
		)
		(fp_line
			(start -0.12065 -0.3048)
			(end -0.67945 -0.3048)
			(stroke
				(width 0.1)
				(type default)
			)
			(layer "B.Fab")
		)
		(fp_line
			(start -0.67945 -0.3048)
			(end -0.67945 0.3048)
			(stroke
				(width 0.1)
				(type default)
			)
			(layer "B.Fab")
		)
		(fp_line
			(start 0.12065 -0.2794)
			(end -0.12065 -0.2794)
			(stroke
				(width 0.1)
				(type default)
			)
			(layer "B.Fab")
		)
		(fp_line
			(start -0.12065 -0.2794)
			(end -0.12065 -0.3048)
			(stroke
				(width 0.1)
				(type default)
			)
			(layer "B.Fab")
		)
		(fp_line
			(start 0.12065 0.2794)
			(end 0.12065 0.3048)
			(stroke
				(width 0.1)
				(type default)
			)
			(layer "B.Fab")
		)
		(fp_line
			(start -0.120396 0.2794)
			(end 0.12065 0.2794)
			(stroke
				(width 0.1)
				(type default)
			)
			(layer "B.Fab")
		)
		(fp_line
			(start 0.67945 0.3048)
			(end 0.67945 -0.305054)
			(stroke
				(width 0.1)
				(type default)
			)
			(layer "B.Fab")
		)
		(fp_line
			(start 0.12065 0.3048)
			(end 0.67945 0.3048)
			(stroke
				(width 0.1)
				(type default)
			)
			(layer "B.Fab")
		)
		(fp_line
			(start -0.120396 0.3048)
			(end -0.120396 0.2794)
			(stroke
				(width 0.1)
				(type default)
			)
			(layer "B.Fab")
		)
		(fp_line
			(start -0.67945 0.3048)
			(end -0.120396 0.3048)
			(stroke
				(width 0.1)
				(type default)
			)
			(layer "B.Fab")
		)
		(pad "1" smd circle
			(at 0.40005 0 270)
			(size 0 0)
			(layers "B.Cu" "B.Mask" "B.Paste")
			(net "I3C_SPD_DDRABCD_CPU0_SDA")
		)
		(pad "2" smd circle
			(at -0.40005 0 270)
			(size 0 0)
			(layers "B.Cu" "B.Mask" "B.Paste")
			(net "I3C_SPD_DDRABCD_CPU0_R_SDA")
		)
	)
	(footprint ""
		(layer "B.Cu")
		(at 98.273108 -190.705232 -90)
		(property "Reference" "R743"
			(at 0 0 90)
			(layer "B.SilkS")
			(hide yes)
			(effects
				(font
					(size 1.27 1.27)
				)
				(justify mirror)
			)
		)
		(property "Value" ""
			(at 0 0 90)
			(layer "B.Fab")
			(effects
				(font
					(size 1.27 1.27)
				)
				(justify mirror)
			)
		)
		(duplicate_pad_numbers_are_jumpers no)
		(fp_line
			(start -0.7874 0.4064)
			(end 0.7874 0.4064)
			(stroke
				(width 0.1524)
				(type default)
			)
			(layer "B.SilkS")
		)
		(fp_line
			(start 0.7874 0.4064)
			(end 0.7874 -0.4064)
			(stroke
				(width 0.1524)
				(type default)
			)
			(layer "B.SilkS")
		)
		(fp_line
			(start -0.7874 -0.4064)
			(end -0.7874 0.4064)
			(stroke
				(width 0.1524)
				(type default)
			)
			(layer "B.SilkS")
		)
		(fp_line
			(start 0.7874 -0.4064)
			(end -0.7874 -0.4064)
			(stroke
				(width 0.1524)
				(type default)
			)
			(layer "B.SilkS")
		)
		(fp_line
			(start -0.67945 0.3048)
			(end -0.120396 0.3048)
			(stroke
				(width 0.1)
				(type default)
			)
			(layer "B.Fab")
		)
		(fp_line
			(start -0.120396 0.3048)
			(end -0.120396 0.2794)
			(stroke
				(width 0.1)
				(type default)
			)
			(layer "B.Fab")
		)
		(fp_line
			(start 0.12065 0.3048)
			(end 0.67945 0.3048)
			(stroke
				(width 0.1)
				(type default)
			)
			(layer "B.Fab")
		)
		(fp_line
			(start 0.67945 0.3048)
			(end 0.67945 -0.305054)
			(stroke
				(width 0.1)
				(type default)
			)
			(layer "B.Fab")
		)
		(fp_line
			(start -0.120396 0.2794)
			(end 0.12065 0.2794)
			(stroke
				(width 0.1)
				(type default)
			)
			(layer "B.Fab")
		)
		(fp_line
			(start 0.12065 0.2794)
			(end 0.12065 0.3048)
			(stroke
				(width 0.1)
				(type default)
			)
			(layer "B.Fab")
		)
		(fp_line
			(start -0.12065 -0.2794)
			(end -0.12065 -0.3048)
			(stroke
				(width 0.1)
				(type default)
			)
			(layer "B.Fab")
		)
		(fp_line
			(start 0.12065 -0.2794)
			(end -0.12065 -0.2794)
			(stroke
				(width 0.1)
				(type default)
			)
			(layer "B.Fab")
		)
		(fp_line
			(start -0.67945 -0.3048)
			(end -0.67945 0.3048)
			(stroke
				(width 0.1)
				(type default)
			)
			(layer "B.Fab")
		)
		(fp_line
			(start -0.12065 -0.3048)
			(end -0.67945 -0.3048)
			(stroke
				(width 0.1)
				(type default)
			)
			(layer "B.Fab")
		)
		(fp_line
			(start 0.12065 -0.305054)
			(end 0.12065 -0.2794)
			(stroke
				(width 0.1)
				(type default)
			)
			(layer "B.Fab")
		)
		(fp_line
			(start 0.67945 -0.305054)
			(end 0.12065 -0.305054)
			(stroke
				(width 0.1)
				(type default)
			)
			(layer "B.Fab")
		)
		(pad "1" smd circle
			(at 0.40005 0 90)
			(size 0 0)
			(layers "B.Cu" "B.Mask" "B.Paste")
			(net "PVNN_TERM_CPU1")
		)
		(pad "2" smd circle
			(at -0.40005 0 90)
			(size 0 0)
			(layers "B.Cu" "B.Mask" "B.Paste")
			(net "JTAG_MUX_CPU1_GTL_TDI")
		)
	)
	(footprint ""
		(layer "B.Cu")
		(at 254.508 -96.738948 180)
		(property "Reference" "R3642"
			(at 0 0 0)
			(layer "B.SilkS")
			(hide yes)
			(effects
				(font
					(size 1.27 1.27)
				)
				(justify mirror)
			)
		)
		(property "Value" ""
			(at 0 0 0)
			(layer "B.Fab")
			(effects
				(font
					(size 1.27 1.27)
				)
				(justify mirror)
			)
		)
		(duplicate_pad_numbers_are_jumpers no)
		(fp_line
			(start 0.7874 0.4064)
			(end 0.7874 -0.4064)
			(stroke
				(width 0.1524)
				(type default)
			)
			(layer "B.SilkS")
		)
		(fp_line
			(start 0.7874 -0.4064)
			(end -0.7874 -0.4064)
			(stroke
				(width 0.1524)
				(type default)
			)
			(layer "B.SilkS")
		)
		(fp_line
			(start -0.7874 0.4064)
			(end 0.7874 0.4064)
			(stroke
				(width 0.1524)
				(type default)
			)
			(layer "B.SilkS")
		)
		(fp_line
			(start -0.7874 -0.4064)
			(end -0.7874 0.4064)
			(stroke
				(width 0.1524)
				(type default)
			)
			(layer "B.SilkS")
		)
		(fp_line
			(start 0.67945 0.3048)
			(end 0.67945 -0.305054)
			(stroke
				(width 0.1)
				(type default)
			)
			(layer "B.Fab")
		)
		(fp_line
			(start 0.67945 -0.305054)
			(end 0.12065 -0.305054)
			(stroke
				(width 0.1)
				(type default)
			)
			(layer "B.Fab")
		)
		(fp_line
			(start 0.12065 0.3048)
			(end 0.67945 0.3048)
			(stroke
				(width 0.1)
				(type default)
			)
			(layer "B.Fab")
		)
		(fp_line
			(start 0.12065 0.2794)
			(end 0.12065 0.3048)
			(stroke
				(width 0.1)
				(type default)
			)
			(layer "B.Fab")
		)
		(fp_line
			(start 0.12065 -0.2794)
			(end -0.12065 -0.2794)
			(stroke
				(width 0.1)
				(type default)
			)
			(layer "B.Fab")
		)
		(fp_line
			(start 0.12065 -0.305054)
			(end 0.12065 -0.2794)
			(stroke
				(width 0.1)
				(type default)
			)
			(layer "B.Fab")
		)
		(fp_line
			(start -0.120396 0.3048)
			(end -0.120396 0.2794)
			(stroke
				(width 0.1)
				(type default)
			)
			(layer "B.Fab")
		)
		(fp_line
			(start -0.120396 0.2794)
			(end 0.12065 0.2794)
			(stroke
				(width 0.1)
				(type default)
			)
			(layer "B.Fab")
		)
		(fp_line
			(start -0.12065 -0.2794)
			(end -0.12065 -0.3048)
			(stroke
				(width 0.1)
				(type default)
			)
			(layer "B.Fab")
		)
		(fp_line
			(start -0.12065 -0.3048)
			(end -0.67945 -0.3048)
			(stroke
				(width 0.1)
				(type default)
			)
			(layer "B.Fab")
		)
		(fp_line
			(start -0.67945 0.3048)
			(end -0.120396 0.3048)
			(stroke
				(width 0.1)
				(type default)
			)
			(layer "B.Fab")
		)
		(fp_line
			(start -0.67945 -0.3048)
			(end -0.67945 0.3048)
			(stroke
				(width 0.1)
				(type default)
			)
			(layer "B.Fab")
		)
		(pad "1" smd circle
			(at 0.40005 0)
			(size 0 0)
			(layers "B.Cu" "B.Mask" "B.Paste")
			(net "P3V3_AUX")
		)
		(pad "2" smd circle
			(at -0.40005 0)
			(size 0 0)
			(layers "B.Cu" "B.Mask" "B.Paste")
			(net "CK440Q_OE_5")
		)
	)
	(footprint ""
		(layer "B.Cu")
		(at 430.586388 -120.798082 180)
		(property "Reference" "PR373"
			(at 0 0 0)
			(layer "B.SilkS")
			(hide yes)
			(effects
				(font
					(size 1.27 1.27)
				)
				(justify mirror)
			)
		)
		(property "Value" ""
			(at 0 0 0)
			(layer "B.Fab")
			(effects
				(font
					(size 1.27 1.27)
				)
				(justify mirror)
			)
		)
		(duplicate_pad_numbers_are_jumpers no)
		(fp_line
			(start 0.7874 0.4064)
			(end 0.7874 -0.4064)
			(stroke
				(width 0.1524)
				(type default)
			)
			(layer "B.SilkS")
		)
		(fp_line
			(start 0.7874 -0.4064)
			(end -0.7874 -0.4064)
			(stroke
				(width 0.1524)
				(type default)
			)
			(layer "B.SilkS")
		)
		(fp_line
			(start -0.7874 0.4064)
			(end 0.7874 0.4064)
			(stroke
				(width 0.1524)
				(type default)
			)
			(layer "B.SilkS")
		)
		(fp_line
			(start -0.7874 -0.4064)
			(end -0.7874 0.4064)
			(stroke
				(width 0.1524)
				(type default)
			)
			(layer "B.SilkS")
		)
		(fp_line
			(start 0.67945 0.3048)
			(end 0.67945 -0.305054)
			(stroke
				(width 0.1)
				(type default)
			)
			(layer "B.Fab")
		)
		(fp_line
			(start 0.67945 -0.305054)
			(end 0.12065 -0.305054)
			(stroke
				(width 0.1)
				(type default)
			)
			(layer "B.Fab")
		)
		(fp_line
			(start 0.12065 0.3048)
			(end 0.67945 0.3048)
			(stroke
				(width 0.1)
				(type default)
			)
			(layer "B.Fab")
		)
		(fp_line
			(start 0.12065 0.2794)
			(end 0.12065 0.3048)
			(stroke
				(width 0.1)
				(type default)
			)
			(layer "B.Fab")
		)
		(fp_line
			(start 0.12065 -0.2794)
			(end -0.12065 -0.2794)
			(stroke
				(width 0.1)
				(type default)
			)
			(layer "B.Fab")
		)
		(fp_line
			(start 0.12065 -0.305054)
			(end 0.12065 -0.2794)
			(stroke
				(width 0.1)
				(type default)
			)
			(layer "B.Fab")
		)
		(fp_line
			(start -0.120396 0.3048)
			(end -0.120396 0.2794)
			(stroke
				(width 0.1)
				(type default)
			)
			(layer "B.Fab")
		)
		(fp_line
			(start -0.120396 0.2794)
			(end 0.12065 0.2794)
			(stroke
				(width 0.1)
				(type default)
			)
			(layer "B.Fab")
		)
		(fp_line
			(start -0.12065 -0.2794)
			(end -0.12065 -0.3048)
			(stroke
				(width 0.1)
				(type default)
			)
			(layer "B.Fab")
		)
		(fp_line
			(start -0.12065 -0.3048)
			(end -0.67945 -0.3048)
			(stroke
				(width 0.1)
				(type default)
			)
			(layer "B.Fab")
		)
		(fp_line
			(start -0.67945 0.3048)
			(end -0.120396 0.3048)
			(stroke
				(width 0.1)
				(type default)
			)
			(layer "B.Fab")
		)
		(fp_line
			(start -0.67945 -0.3048)
			(end -0.67945 0.3048)
			(stroke
				(width 0.1)
				(type default)
			)
			(layer "B.Fab")
		)
		(pad "1" smd circle
			(at 0.40005 0)
			(size 0 0)
			(layers "B.Cu" "B.Mask" "B.Paste")
			(net "PVCCD_HV_CPU0_ISENSE_N")
		)
		(pad "2" smd circle
			(at -0.40005 0)
			(size 0 0)
			(layers "B.Cu" "B.Mask" "B.Paste")
			(net "GND")
		)
	)
)
